# T6G (Grand Teton) — schematic netlist excerpt (pin names and nets, part order shuffled) for the footprints in the layout excerpt that follows; sources: Cadence DE-HDL packaged netlist, KiCad conversion of 04192023_DAF0TMB3IC0_F0TG_MB_C_brd_V02_OCP.brd

C612  Q_CAP  0.1UF 25V 10% X7R  pkg 0402  page 160 : A = PVDD18_S5_P0 ; B = GND
R4570  Q_RES  0 5% EMPTY  pkg 0402LF  page 124 : A = GPU_3V3IO_RSVD3 ; B = GPU_3V3IO_RSVD3_ISO
R6903  Q_RES  0 5% CHIP  pkg 0201LF  page 354 : A = NCF_CPU1_P3_GND ; B = GND

(kicad_pcb
	(version 20260206)
	(generator "pcbnew")
	(generator_version "10.0")
	(general
		(thickness 1.6)
		(legacy_teardrops no)
	)
	(paper "A4")
	(title_block
		(title "04192023_DAF0TMB3IC0_F0TG_MB_C_brd_V02_OCP.brd")
		(comment 1 "Grand Teton / footprints 7239-7241 of 8354")
	)
	(layers
		(0 "F.Cu" signal "TOP")
		(4 "In1.Cu" signal "GND")
		(6 "In2.Cu" signal "IN1")
		(8 "In3.Cu" signal "GND1")
		(10 "In4.Cu" signal "IN2")
		(12 "In5.Cu" signal "GND2")
		(14 "In6.Cu" signal "IN3")
		(16 "In7.Cu" signal "GND3")
		(18 "In8.Cu" signal "VCC")
		(20 "In9.Cu" signal "VCC1")
		(22 "In10.Cu" signal "GND4")
		(24 "In11.Cu" signal "IN4")
		(26 "In12.Cu" signal "GND5")
		(28 "In13.Cu" signal "IN5")
		(30 "In14.Cu" signal "GND6")
		(32 "In15.Cu" signal "IN6")
		(34 "In16.Cu" signal "GND7")
		(2 "B.Cu" signal "BOTTOM")
		(9 "F.Adhes" user "F.Adhesive")
		(11 "B.Adhes" user "B.Adhesive")
		(13 "F.Paste" user "Package Geometry/Pastemask Top")
		(15 "B.Paste" user "Package Geometry/Pastemask Bottom")
		(5 "F.SilkS" user "Ref Des/Silkscreen Top")
		(7 "B.SilkS" user "Ref Des/Silkscreen Bottom")
		(1 "F.Mask" user "Board Geometry/Soldermask Top")
		(3 "B.Mask" user "Board Geometry/Soldermask Bottom")
		(17 "Dwgs.User" user "User.Drawings")
		(19 "Cmts.User" user "User.Comments")
		(21 "Eco1.User" user "User.Eco1")
		(23 "Eco2.User" user "User.Eco2")
		(25 "Edge.Cuts" user "Board Geometry/Outline")
		(27 "Margin" user)
		(31 "F.CrtYd" user "Package Geometry/Place Bound Top")
		(29 "B.CrtYd" user "Package Geometry/Place Bound Bottom")
		(35 "F.Fab" user "Ref Des/Assembly Top")
		(33 "B.Fab" user "Ref Des/Assembly Bottom")
	)
	(footprint ""
		(layer "B.Cu")
		(at 430.119282 -437.392572 -90)
		(property "Reference" "R4570"
			(at 0 0 90)
			(layer "B.SilkS")
			(hide yes)
			(effects
				(font
					(size 1.27 1.27)
				)
				(justify mirror)
			)
		)
		(property "Value" ""
			(at 0 0 90)
			(layer "B.Fab")
			(effects
				(font
					(size 1.27 1.27)
				)
				(justify mirror)
			)
		)
		(duplicate_pad_numbers_are_jumpers no)
		(fp_line
			(start -0.7874 0.4064)
			(end 0.7874 0.4064)
			(stroke
				(width 0.1524)
				(type default)
			)
			(layer "B.SilkS")
		)
		(fp_line
			(start 0.7874 0.4064)
			(end 0.7874 -0.4064)
			(stroke
				(width 0.1524)
				(type default)
			)
			(layer "B.SilkS")
		)
		(fp_line
			(start -0.7874 -0.4064)
			(end -0.7874 0.4064)
			(stroke
				(width 0.1524)
				(type default)
			)
			(layer "B.SilkS")
		)
		(fp_line
			(start 0.7874 -0.4064)
			(end -0.7874 -0.4064)
			(stroke
				(width 0.1524)
				(type default)
			)
			(layer "B.SilkS")
		)
		(fp_line
			(start -0.67945 0.3048)
			(end -0.120396 0.3048)
			(stroke
				(width 0.1)
				(type default)
			)
			(layer "B.Fab")
		)
		(fp_line
			(start -0.120396 0.3048)
			(end -0.120396 0.2794)
			(stroke
				(width 0.1)
				(type default)
			)
			(layer "B.Fab")
		)
		(fp_line
			(start 0.12065 0.3048)
			(end 0.67945 0.3048)
			(stroke
				(width 0.1)
				(type default)
			)
			(layer "B.Fab")
		)
		(fp_line
			(start 0.67945 0.3048)
			(end 0.67945 -0.305054)
			(stroke
				(width 0.1)
				(type default)
			)
			(layer "B.Fab")
		)
		(fp_line
			(start -0.120396 0.2794)
			(end 0.12065 0.2794)
			(stroke
				(width 0.1)
				(type default)
			)
			(layer "B.Fab")
		)
		(fp_line
			(start 0.12065 0.2794)
			(end 0.12065 0.3048)
			(stroke
				(width 0.1)
				(type default)
			)
			(layer "B.Fab")
		)
		(fp_line
			(start -0.12065 -0.2794)
			(end -0.12065 -0.3048)
			(stroke
				(width 0.1)
				(type default)
			)
			(layer "B.Fab")
		)
		(fp_line
			(start 0.12065 -0.2794)
			(end -0.12065 -0.2794)
			(stroke
				(width 0.1)
				(type default)
			)
			(layer "B.Fab")
		)
		(fp_line
			(start -0.67945 -0.3048)
			(end -0.67945 0.3048)
			(stroke
				(width 0.1)
				(type default)
			)
			(layer "B.Fab")
		)
		(fp_line
			(start -0.12065 -0.3048)
			(end -0.67945 -0.3048)
			(stroke
				(width 0.1)
				(type default)
			)
			(layer "B.Fab")
		)
		(fp_line
			(start 0.12065 -0.305054)
			(end 0.12065 -0.2794)
			(stroke
				(width 0.1)
				(type default)
			)
			(layer "B.Fab")
		)
		(fp_line
			(start 0.67945 -0.305054)
			(end 0.12065 -0.305054)
			(stroke
				(width 0.1)
				(type default)
			)
			(layer "B.Fab")
		)
		(pad "1" smd circle
			(at 0.40005 0 90)
			(size 0 0)
			(layers "B.Cu" "B.Mask" "B.Paste")
			(net "GPU_3V3IO_RSVD3")
		)
		(pad "2" smd circle
			(at -0.40005 0 90)
			(size 0 0)
			(layers "B.Cu" "B.Mask" "B.Paste")
			(net "GPU_3V3IO_RSVD3_ISO")
		)
	)
	(footprint ""
		(layer "B.Cu")
		(at 137.153142 -382.8796 180)
		(property "Reference" "R6903"
			(at 0 0 0)
			(layer "B.SilkS")
			(hide yes)
			(effects
				(font
					(size 1.27 1.27)
				)
				(justify mirror)
			)
		)
		(property "Value" ""
			(at 0 0 0)
			(layer "B.Fab")
			(effects
				(font
					(size 1.27 1.27)
				)
				(justify mirror)
			)
		)
		(duplicate_pad_numbers_are_jumpers no)
		(fp_line
			(start 0.32512 0.175006)
			(end 0.32512 -0.175006)
			(stroke
				(width 0.1)
				(type default)
			)
			(layer "B.Fab")
		)
		(fp_line
			(start 0.32512 -0.175006)
			(end -0.32512 -0.175006)
			(stroke
				(width 0.1)
				(type default)
			)
			(layer "B.Fab")
		)
		(fp_line
			(start -0.32512 0.175006)
			(end 0.32512 0.175006)
			(stroke
				(width 0.1)
				(type default)
			)
			(layer "B.Fab")
		)
		(fp_line
			(start -0.32512 -0.175006)
			(end -0.32512 0.175006)
			(stroke
				(width 0.1)
				(type default)
			)
			(layer "B.Fab")
		)
		(pad "1" smd rect
			(at 0.2667 0)
			(size 0.3048 0.381)
			(layers "B.Cu" "B.Mask" "B.Paste")
			(net "NCF_CPU1_P3_GND")
		)
		(pad "2" smd rect
			(at -0.2667 0 180)
			(size 0.3048 0.381)
			(layers "B.Cu" "B.Mask" "B.Paste")
			(net "GND")
		)
	)
	(footprint ""
		(layer "B.Cu")
		(at 241.173 -224.028 90)
		(property "Reference" "C612"
			(at 0 0 90)
			(layer "B.SilkS")
			(hide yes)
			(effects
				(font
					(size 1.27 1.27)
				)
				(justify mirror)
			)
		)
		(property "Value" ""
			(at 0 0 90)
			(layer "B.Fab")
			(effects
				(font
					(size 1.27 1.27)
				)
				(justify mirror)
			)
		)
		(duplicate_pad_numbers_are_jumpers no)
		(fp_line
			(start 0.7874 -0.4064)
			(end -0.7874 -0.4064)
			(stroke
				(width 0.1524)
				(type default)
			)
			(layer "B.SilkS")
		)
		(fp_line
			(start -0.7874 -0.4064)
			(end -0.7874 0.4064)
			(stroke
				(width 0.1524)
				(type default)
			)
			(layer "B.SilkS")
		)
		(fp_line
			(start 0.7874 0.4064)
			(end 0.7874 -0.4064)
			(stroke
				(width 0.1524)
				(type default)
			)
			(layer "B.SilkS")
		)
		(fp_line
			(start -0.7874 0.4064)
			(end 0.7874 0.4064)
			(stroke
				(width 0.1524)
				(type default)
			)
			(layer "B.SilkS")
		)
		(fp_line
			(start 0.67945 -0.305054)
			(end 0.12065 -0.305054)
			(stroke
				(width 0.1)
				(type default)
			)
			(layer "B.Fab")
		)
		(fp_line
			(start 0.12065 -0.305054)
			(end 0.12065 -0.2794)
			(stroke
				(width 0.1)
				(type default)
			)
			(layer "B.Fab")
		)
		(fp_line
			(start -0.12065 -0.3048)
			(end -0.67945 -0.3048)
			(stroke
				(width 0.1)
				(type default)
			)
			(layer "B.Fab")
		)
		(fp_line
			(start -0.67945 -0.3048)
			(end -0.67945 0.3048)
			(stroke
				(width 0.1)
				(type default)
			)
			(layer "B.Fab")
		)
		(fp_line
			(start 0.12065 -0.2794)
			(end -0.12065 -0.2794)
			(stroke
				(width 0.1)
				(type default)
			)
			(layer "B.Fab")
		)
		(fp_line
			(start -0.12065 -0.2794)
			(end -0.12065 -0.3048)
			(stroke
				(width 0.1)
				(type default)
			)
			(layer "B.Fab")
		)
		(fp_line
			(start 0.12065 0.2794)
			(end 0.12065 0.3048)
			(stroke
				(width 0.1)
				(type default)
			)
			(layer "B.Fab")
		)
		(fp_line
			(start -0.120396 0.2794)
			(end 0.12065 0.2794)
			(stroke
				(width 0.1)
				(type default)
			)
			(layer "B.Fab")
		)
		(fp_line
			(start 0.67945 0.3048)
			(end 0.67945 -0.305054)
			(stroke
				(width 0.1)
				(type default)
			)
			(layer "B.Fab")
		)
		(fp_line
			(start 0.12065 0.3048)
			(end 0.67945 0.3048)
			(stroke
				(width 0.1)
				(type default)
			)
			(layer "B.Fab")
		)
		(fp_line
			(start -0.120396 0.3048)
			(end -0.120396 0.2794)
			(stroke
				(width 0.1)
				(type default)
			)
			(layer "B.Fab")
		)
		(fp_line
			(start -0.67945 0.3048)
			(end -0.120396 0.3048)
			(stroke
				(width 0.1)
				(type default)
			)
			(layer "B.Fab")
		)
		(pad "1" smd circle
			(at 0.40005 0 270)
			(size 0 0)
			(layers "B.Cu" "B.Mask" "B.Paste")
			(net "PVDD18_S5_P0")
		)
		(pad "2" smd circle
			(at -0.40005 0 270)
			(size 0 0)
			(layers "B.Cu" "B.Mask" "B.Paste")
			(net "GND")
		)
	)
)
